(kicad_pcb
	(version 20260206)
	(generator "pcbnew")
	(generator_version "10.0")
	(general
		(thickness 1.6)
		(legacy_teardrops no)
	)
	(paper "A4")
	(title_block
		(title "03242023_DA0F0TMBIJ0_F0T_Motherboard_J_brd_V01_OCP.brd")
		(comment 1 "Grand Teton / footprints 4753-4759 of 6105")
	)
	(layers
		(0 "F.Cu" signal "TOP")
		(4 "In1.Cu" signal "GND")
		(6 "In2.Cu" signal "IN1")
		(8 "In3.Cu" signal "GND1")
		(10 "In4.Cu" signal "IN2")
		(12 "In5.Cu" signal "GND2")
		(14 "In6.Cu" signal "IN3")
		(16 "In7.Cu" signal "GND3")
		(18 "In8.Cu" signal "VCC")
		(20 "In9.Cu" signal "VCC1")
		(22 "In10.Cu" signal "GND4")
		(24 "In11.Cu" signal "IN4")
		(26 "In12.Cu" signal "GND5")
		(28 "In13.Cu" signal "IN5")
		(30 "In14.Cu" signal "GND6")
		(32 "In15.Cu" signal "IN6")
		(34 "In16.Cu" signal "GND7")
		(2 "B.Cu" signal "BOTTOM")
		(9 "F.Adhes" user "F.Adhesive")
		(11 "B.Adhes" user "B.Adhesive")
		(13 "F.Paste" user "Package Geometry/Pastemask Top")
		(15 "B.Paste" user "Package Geometry/Pastemask Bottom")
		(5 "F.SilkS" user "Ref Des/Silkscreen Top")
		(7 "B.SilkS" user "Ref Des/Silkscreen Bottom")
		(1 "F.Mask" user "Board Geometry/Soldermask Top")
		(3 "B.Mask" user "Board Geometry/Soldermask Bottom")
		(17 "Dwgs.User" user "User.Drawings")
		(19 "Cmts.User" user "User.Comments")
		(21 "Eco1.User" user "User.Eco1")
		(23 "Eco2.User" user "User.Eco2")
		(25 "Edge.Cuts" user "Board Geometry/Outline")
		(27 "Margin" user)
		(31 "F.CrtYd" user "Package Geometry/Place Bound Top")
		(29 "B.CrtYd" user "Package Geometry/Place Bound Bottom")
		(35 "F.Fab" user "Ref Des/Assembly Top")
		(33 "B.Fab" user "Ref Des/Assembly Bottom")
	)
	(footprint ""
		(layer "B.Cu")
		(at 160.28924 -12.774168 90)
		(property "Reference" "R3113"
			(at 0 0 90)
			(layer "B.SilkS")
			(hide yes)
			(effects
				(font
					(size 1.27 1.27)
				)
				(justify mirror)
			)
		)
		(property "Value" ""
			(at 0 0 90)
			(layer "B.Fab")
			(effects
				(font
					(size 1.27 1.27)
				)
				(justify mirror)
			)
		)
		(duplicate_pad_numbers_are_jumpers no)
		(fp_line
			(start 0.7874 -0.4064)
			(end -0.7874 -0.4064)
			(stroke
				(width 0.1524)
				(type default)
			)
			(layer "B.SilkS")
		)
		(fp_line
			(start -0.7874 -0.4064)
			(end -0.7874 0.4064)
			(stroke
				(width 0.1524)
				(type default)
			)
			(layer "B.SilkS")
		)
		(fp_line
			(start 0.7874 0.4064)
			(end 0.7874 -0.4064)
			(stroke
				(width 0.1524)
				(type default)
			)
			(layer "B.SilkS")
		)
		(fp_line
			(start -0.7874 0.4064)
			(end 0.7874 0.4064)
			(stroke
				(width 0.1524)
				(type default)
			)
			(layer "B.SilkS")
		)
		(fp_line
			(start 0.67945 -0.305054)
			(end 0.12065 -0.305054)
			(stroke
				(width 0.1)
				(type default)
			)
			(layer "B.Fab")
		)
		(fp_line
			(start 0.12065 -0.305054)
			(end 0.12065 -0.2794)
			(stroke
				(width 0.1)
				(type default)
			)
			(layer "B.Fab")
		)
		(fp_line
			(start -0.12065 -0.3048)
			(end -0.67945 -0.3048)
			(stroke
				(width 0.1)
				(type default)
			)
			(layer "B.Fab")
		)
		(fp_line
			(start -0.67945 -0.3048)
			(end -0.67945 0.3048)
			(stroke
				(width 0.1)
				(type default)
			)
			(layer "B.Fab")
		)
		(fp_line
			(start 0.12065 -0.2794)
			(end -0.12065 -0.2794)
			(stroke
				(width 0.1)
				(type default)
			)
			(layer "B.Fab")
		)
		(fp_line
			(start -0.12065 -0.2794)
			(end -0.12065 -0.3048)
			(stroke
				(width 0.1)
				(type default)
			)
			(layer "B.Fab")
		)
		(fp_line
			(start 0.12065 0.2794)
			(end 0.12065 0.3048)
			(stroke
				(width 0.1)
				(type default)
			)
			(layer "B.Fab")
		)
		(fp_line
			(start -0.120396 0.2794)
			(end 0.12065 0.2794)
			(stroke
				(width 0.1)
				(type default)
			)
			(layer "B.Fab")
		)
		(fp_line
			(start 0.67945 0.3048)
			(end 0.67945 -0.305054)
			(stroke
				(width 0.1)
				(type default)
			)
			(layer "B.Fab")
		)
		(fp_line
			(start 0.12065 0.3048)
			(end 0.67945 0.3048)
			(stroke
				(width 0.1)
				(type default)
			)
			(layer "B.Fab")
		)
		(fp_line
			(start -0.120396 0.3048)
			(end -0.120396 0.2794)
			(stroke
				(width 0.1)
				(type default)
			)
			(layer "B.Fab")
		)
		(fp_line
			(start -0.67945 0.3048)
			(end -0.120396 0.3048)
			(stroke
				(width 0.1)
				(type default)
			)
			(layer "B.Fab")
		)
		(pad "1" smd circle
			(at 0.40005 0 270)
			(size 0 0)
			(layers "B.Cu" "B.Mask" "B.Paste")
			(net "SMB_FAN_3V3AUX_SCL")
		)
		(pad "2" smd circle
			(at -0.40005 0 270)
			(size 0 0)
			(layers "B.Cu" "B.Mask" "B.Paste")
			(net "SMB_FAN_3V3AUX_R_SCL")
		)
	)
	(footprint ""
		(layer "B.Cu")
		(at 85.9282 -338.137246 -90)
		(property "Reference" "PR293"
			(at 0 0 90)
			(layer "B.SilkS")
			(hide yes)
			(effects
				(font
					(size 1.27 1.27)
				)
				(justify mirror)
			)
		)
		(property "Value" ""
			(at 0 0 90)
			(layer "B.Fab")
			(effects
				(font
					(size 1.27 1.27)
				)
				(justify mirror)
			)
		)
		(duplicate_pad_numbers_are_jumpers no)
		(fp_line
			(start -0.7874 0.4064)
			(end 0.7874 0.4064)
			(stroke
				(width 0.1524)
				(type default)
			)
			(layer "B.SilkS")
		)
		(fp_line
			(start 0.7874 0.4064)
			(end 0.7874 -0.4064)
			(stroke
				(width 0.1524)
				(type default)
			)
			(layer "B.SilkS")
		)
		(fp_line
			(start -0.7874 -0.4064)
			(end -0.7874 0.4064)
			(stroke
				(width 0.1524)
				(type default)
			)
			(layer "B.SilkS")
		)
		(fp_line
			(start 0.7874 -0.4064)
			(end -0.7874 -0.4064)
			(stroke
				(width 0.1524)
				(type default)
			)
			(layer "B.SilkS")
		)
		(fp_line
			(start -0.67945 0.3048)
			(end -0.120396 0.3048)
			(stroke
				(width 0.1)
				(type default)
			)
			(layer "B.Fab")
		)
		(fp_line
			(start -0.120396 0.3048)
			(end -0.120396 0.2794)
			(stroke
				(width 0.1)
				(type default)
			)
			(layer "B.Fab")
		)
		(fp_line
			(start 0.12065 0.3048)
			(end 0.67945 0.3048)
			(stroke
				(width 0.1)
				(type default)
			)
			(layer "B.Fab")
		)
		(fp_line
			(start 0.67945 0.3048)
			(end 0.67945 -0.305054)
			(stroke
				(width 0.1)
				(type default)
			)
			(layer "B.Fab")
		)
		(fp_line
			(start -0.120396 0.2794)
			(end 0.12065 0.2794)
			(stroke
				(width 0.1)
				(type default)
			)
			(layer "B.Fab")
		)
		(fp_line
			(start 0.12065 0.2794)
			(end 0.12065 0.3048)
			(stroke
				(width 0.1)
				(type default)
			)
			(layer "B.Fab")
		)
		(fp_line
			(start -0.12065 -0.2794)
			(end -0.12065 -0.3048)
			(stroke
				(width 0.1)
				(type default)
			)
			(layer "B.Fab")
		)
		(fp_line
			(start 0.12065 -0.2794)
			(end -0.12065 -0.2794)
			(stroke
				(width 0.1)
				(type default)
			)
			(layer "B.Fab")
		)
		(fp_line
			(start -0.67945 -0.3048)
			(end -0.67945 0.3048)
			(stroke
				(width 0.1)
				(type default)
			)
			(layer "B.Fab")
		)
		(fp_line
			(start -0.12065 -0.3048)
			(end -0.67945 -0.3048)
			(stroke
				(width 0.1)
				(type default)
			)
			(layer "B.Fab")
		)
		(fp_line
			(start 0.12065 -0.305054)
			(end 0.12065 -0.2794)
			(stroke
				(width 0.1)
				(type default)
			)
			(layer "B.Fab")
		)
		(fp_line
			(start 0.67945 -0.305054)
			(end 0.12065 -0.305054)
			(stroke
				(width 0.1)
				(type default)
			)
			(layer "B.Fab")
		)
		(pad "1" smd circle
			(at 0.40005 0 90)
			(size 0 0)
			(layers "B.Cu" "B.Mask" "B.Paste")
			(net "PVCCIN_CPU1_PVCC")
		)
		(pad "2" smd circle
			(at -0.40005 0 90)
			(size 0 0)
			(layers "B.Cu" "B.Mask" "B.Paste")
			(net "PVCCIN_CPU1_VDD6")
		)
	)
	(footprint ""
		(layer "B.Cu")
		(at 17.779492 -97.342198 90)
		(property "Reference" "C2040"
			(at 0 0 90)
			(layer "B.SilkS")
			(hide yes)
			(effects
				(font
					(size 1.27 1.27)
				)
				(justify mirror)
			)
		)
		(property "Value" ""
			(at 0 0 90)
			(layer "B.Fab")
			(effects
				(font
					(size 1.27 1.27)
				)
				(justify mirror)
			)
		)
		(duplicate_pad_numbers_are_jumpers no)
		(fp_line
			(start 0.7874 -0.4064)
			(end -0.7874 -0.4064)
			(stroke
				(width 0.1524)
				(type default)
			)
			(layer "B.SilkS")
		)
		(fp_line
			(start -0.7874 -0.4064)
			(end -0.7874 0.4064)
			(stroke
				(width 0.1524)
				(type default)
			)
			(layer "B.SilkS")
		)
		(fp_line
			(start 0.7874 0.4064)
			(end 0.7874 -0.4064)
			(stroke
				(width 0.1524)
				(type default)
			)
			(layer "B.SilkS")
		)
		(fp_line
			(start -0.7874 0.4064)
			(end 0.7874 0.4064)
			(stroke
				(width 0.1524)
				(type default)
			)
			(layer "B.SilkS")
		)
		(fp_line
			(start 0.67945 -0.305054)
			(end 0.12065 -0.305054)
			(stroke
				(width 0.1)
				(type default)
			)
			(layer "B.Fab")
		)
		(fp_line
			(start 0.12065 -0.305054)
			(end 0.12065 -0.2794)
			(stroke
				(width 0.1)
				(type default)
			)
			(layer "B.Fab")
		)
		(fp_line
			(start -0.12065 -0.3048)
			(end -0.67945 -0.3048)
			(stroke
				(width 0.1)
				(type default)
			)
			(layer "B.Fab")
		)
		(fp_line
			(start -0.67945 -0.3048)
			(end -0.67945 0.3048)
			(stroke
				(width 0.1)
				(type default)
			)
			(layer "B.Fab")
		)
		(fp_line
			(start 0.12065 -0.2794)
			(end -0.12065 -0.2794)
			(stroke
				(width 0.1)
				(type default)
			)
			(layer "B.Fab")
		)
		(fp_line
			(start -0.12065 -0.2794)
			(end -0.12065 -0.3048)
			(stroke
				(width 0.1)
				(type default)
			)
			(layer "B.Fab")
		)
		(fp_line
			(start 0.12065 0.2794)
			(end 0.12065 0.3048)
			(stroke
				(width 0.1)
				(type default)
			)
			(layer "B.Fab")
		)
		(fp_line
			(start -0.120396 0.2794)
			(end 0.12065 0.2794)
			(stroke
				(width 0.1)
				(type default)
			)
			(layer "B.Fab")
		)
		(fp_line
			(start 0.67945 0.3048)
			(end 0.67945 -0.305054)
			(stroke
				(width 0.1)
				(type default)
			)
			(layer "B.Fab")
		)
		(fp_line
			(start 0.12065 0.3048)
			(end 0.67945 0.3048)
			(stroke
				(width 0.1)
				(type default)
			)
			(layer "B.Fab")
		)
		(fp_line
			(start -0.120396 0.3048)
			(end -0.120396 0.2794)
			(stroke
				(width 0.1)
				(type default)
			)
			(layer "B.Fab")
		)
		(fp_line
			(start -0.67945 0.3048)
			(end -0.120396 0.3048)
			(stroke
				(width 0.1)
				(type default)
			)
			(layer "B.Fab")
		)
		(pad "1" smd circle
			(at 0.40005 0 270)
			(size 0 0)
			(layers "B.Cu" "B.Mask" "B.Paste")
			(net "P3V3_AUX_USB_HUB")
		)
		(pad "2" smd circle
			(at -0.40005 0 270)
			(size 0 0)
			(layers "B.Cu" "B.Mask" "B.Paste")
			(net "GND")
		)
	)
	(footprint ""
		(layer "B.Cu")
		(at 331.01788 -27.701748 90)
		(property "Reference" "R4095"
			(at 0 0 90)
			(layer "B.SilkS")
			(hide yes)
			(effects
				(font
					(size 1.27 1.27)
				)
				(justify mirror)
			)
		)
		(property "Value" ""
			(at 0 0 90)
			(layer "B.Fab")
			(effects
				(font
					(size 1.27 1.27)
				)
				(justify mirror)
			)
		)
		(duplicate_pad_numbers_are_jumpers no)
		(fp_line
			(start 0.7874 -0.4064)
			(end -0.7874 -0.4064)
			(stroke
				(width 0.1524)
				(type default)
			)
			(layer "B.SilkS")
		)
		(fp_line
			(start -0.7874 -0.4064)
			(end -0.7874 0.4064)
			(stroke
				(width 0.1524)
				(type default)
			)
			(layer "B.SilkS")
		)
		(fp_line
			(start 0.7874 0.4064)
			(end 0.7874 -0.4064)
			(stroke
				(width 0.1524)
				(type default)
			)
			(layer "B.SilkS")
		)
		(fp_line
			(start -0.7874 0.4064)
			(end 0.7874 0.4064)
			(stroke
				(width 0.1524)
				(type default)
			)
			(layer "B.SilkS")
		)
		(fp_line
			(start 0.67945 -0.305054)
			(end 0.12065 -0.305054)
			(stroke
				(width 0.1)
				(type default)
			)
			(layer "B.Fab")
		)
		(fp_line
			(start 0.12065 -0.305054)
			(end 0.12065 -0.2794)
			(stroke
				(width 0.1)
				(type default)
			)
			(layer "B.Fab")
		)
		(fp_line
			(start -0.12065 -0.3048)
			(end -0.67945 -0.3048)
			(stroke
				(width 0.1)
				(type default)
			)
			(layer "B.Fab")
		)
		(fp_line
			(start -0.67945 -0.3048)
			(end -0.67945 0.3048)
			(stroke
				(width 0.1)
				(type default)
			)
			(layer "B.Fab")
		)
		(fp_line
			(start 0.12065 -0.2794)
			(end -0.12065 -0.2794)
			(stroke
				(width 0.1)
				(type default)
			)
			(layer "B.Fab")
		)
		(fp_line
			(start -0.12065 -0.2794)
			(end -0.12065 -0.3048)
			(stroke
				(width 0.1)
				(type default)
			)
			(layer "B.Fab")
		)
		(fp_line
			(start 0.12065 0.2794)
			(end 0.12065 0.3048)
			(stroke
				(width 0.1)
				(type default)
			)
			(layer "B.Fab")
		)
		(fp_line
			(start -0.120396 0.2794)
			(end 0.12065 0.2794)
			(stroke
				(width 0.1)
				(type default)
			)
			(layer "B.Fab")
		)
		(fp_line
			(start 0.67945 0.3048)
			(end 0.67945 -0.305054)
			(stroke
				(width 0.1)
				(type default)
			)
			(layer "B.Fab")
		)
		(fp_line
			(start 0.12065 0.3048)
			(end 0.67945 0.3048)
			(stroke
				(width 0.1)
				(type default)
			)
			(layer "B.Fab")
		)
		(fp_line
			(start -0.120396 0.3048)
			(end -0.120396 0.2794)
			(stroke
				(width 0.1)
				(type default)
			)
			(layer "B.Fab")
		)
		(fp_line
			(start -0.67945 0.3048)
			(end -0.120396 0.3048)
			(stroke
				(width 0.1)
				(type default)
			)
			(layer "B.Fab")
		)
		(pad "1" smd circle
			(at 0.40005 0 270)
			(size 0 0)
			(layers "B.Cu" "B.Mask" "B.Paste")
			(net "PD_PCH_GPPC_A_19")
		)
		(pad "2" smd circle
			(at -0.40005 0 270)
			(size 0 0)
			(layers "B.Cu" "B.Mask" "B.Paste")
			(net "GND")
		)
	)
	(footprint ""
		(layer "B.Cu")
		(at 426.970444 -362.107226 90)
		(property "Reference" "PC1181_P0_3"
			(at 0 0 90)
			(layer "B.SilkS")
			(hide yes)
			(effects
				(font
					(size 1.27 1.27)
				)
				(justify mirror)
			)
		)
		(property "Value" ""
			(at 0 0 90)
			(layer "B.Fab")
			(effects
				(font
					(size 1.27 1.27)
				)
				(justify mirror)
			)
		)
		(duplicate_pad_numbers_are_jumpers no)
		(fp_line
			(start 1.524 -0.762)
			(end -1.524 -0.762)
			(stroke
				(width 0.1524)
				(type default)
			)
			(layer "B.SilkS")
		)
		(fp_line
			(start -1.524 -0.762)
			(end -1.524 0.762)
			(stroke
				(width 0.1524)
				(type default)
			)
			(layer "B.SilkS")
		)
		(fp_line
			(start 1.524 0.762)
			(end 1.524 -0.762)
			(stroke
				(width 0.1524)
				(type default)
			)
			(layer "B.SilkS")
		)
		(fp_line
			(start -1.524 0.762)
			(end 1.524 0.762)
			(stroke
				(width 0.1524)
				(type default)
			)
			(layer "B.SilkS")
		)
		(fp_line
			(start 1.1049 -0.724916)
			(end 1.1049 0.724916)
			(stroke
				(width 0.1)
				(type default)
			)
			(layer "B.Fab")
		)
		(fp_line
			(start -1.1049 -0.724916)
			(end 1.1049 -0.724916)
			(stroke
				(width 0.1)
				(type default)
			)
			(layer "B.Fab")
		)
		(fp_line
			(start 1.1049 0.724916)
			(end -1.1049 0.724916)
			(stroke
				(width 0.1)
				(type default)
			)
			(layer "B.Fab")
		)
		(fp_line
			(start -1.1049 0.724916)
			(end -1.1049 -0.724916)
			(stroke
				(width 0.1)
				(type default)
			)
			(layer "B.Fab")
		)
		(pad "1" smd rect
			(at 0.889 0 90)
			(size 1.016 1.27)
			(layers "B.Cu" "B.Mask" "B.Paste")
			(net "SW_P12V_PVCCFA_EHV_FIVRA_CPU0_R")
		)
		(pad "2" smd rect
			(at -0.889 0 90)
			(size 1.016 1.27)
			(layers "B.Cu" "B.Mask" "B.Paste")
			(net "GND")
		)
	)
	(footprint ""
		(layer "B.Cu")
		(at 81.74863 -52.082446)
		(property "Reference" "R3826"
			(at 0 0 0)
			(layer "B.SilkS")
			(hide yes)
			(effects
				(font
					(size 1.27 1.27)
				)
				(justify mirror)
			)
		)
		(property "Value" ""
			(at 0 0 0)
			(layer "B.Fab")
			(effects
				(font
					(size 1.27 1.27)
				)
				(justify mirror)
			)
		)
		(duplicate_pad_numbers_are_jumpers no)
		(fp_line
			(start -0.7874 -0.4064)
			(end -0.7874 0.4064)
			(stroke
				(width 0.1524)
				(type default)
			)
			(layer "B.SilkS")
		)
		(fp_line
			(start -0.7874 0.4064)
			(end 0.7874 0.4064)
			(stroke
				(width 0.1524)
				(type default)
			)
			(layer "B.SilkS")
		)
		(fp_line
			(start 0.7874 -0.4064)
			(end -0.7874 -0.4064)
			(stroke
				(width 0.1524)
				(type default)
			)
			(layer "B.SilkS")
		)
		(fp_line
			(start 0.7874 0.4064)
			(end 0.7874 -0.4064)
			(stroke
				(width 0.1524)
				(type default)
			)
			(layer "B.SilkS")
		)
		(fp_line
			(start -0.67945 -0.3048)
			(end -0.67945 0.3048)
			(stroke
				(width 0.1)
				(type default)
			)
			(layer "B.Fab")
		)
		(fp_line
			(start -0.67945 0.3048)
			(end -0.120396 0.3048)
			(stroke
				(width 0.1)
				(type default)
			)
			(layer "B.Fab")
		)
		(fp_line
			(start -0.12065 -0.3048)
			(end -0.67945 -0.3048)
			(stroke
				(width 0.1)
				(type default)
			)
			(layer "B.Fab")
		)
		(fp_line
			(start -0.12065 -0.2794)
			(end -0.12065 -0.3048)
			(stroke
				(width 0.1)
				(type default)
			)
			(layer "B.Fab")
		)
		(fp_line
			(start -0.120396 0.2794)
			(end 0.12065 0.2794)
			(stroke
				(width 0.1)
				(type default)
			)
			(layer "B.Fab")
		)
		(fp_line
			(start -0.120396 0.3048)
			(end -0.120396 0.2794)
			(stroke
				(width 0.1)
				(type default)
			)
			(layer "B.Fab")
		)
		(fp_line
			(start 0.12065 -0.305054)
			(end 0.12065 -0.2794)
			(stroke
				(width 0.1)
				(type default)
			)
			(layer "B.Fab")
		)
		(fp_line
			(start 0.12065 -0.2794)
			(end -0.12065 -0.2794)
			(stroke
				(width 0.1)
				(type default)
			)
			(layer "B.Fab")
		)
		(fp_line
			(start 0.12065 0.2794)
			(end 0.12065 0.3048)
			(stroke
				(width 0.1)
				(type default)
			)
			(layer "B.Fab")
		)
		(fp_line
			(start 0.12065 0.3048)
			(end 0.67945 0.3048)
			(stroke
				(width 0.1)
				(type default)
			)
			(layer "B.Fab")
		)
		(fp_line
			(start 0.67945 -0.305054)
			(end 0.12065 -0.305054)
			(stroke
				(width 0.1)
				(type default)
			)
			(layer "B.Fab")
		)
		(fp_line
			(start 0.67945 0.3048)
			(end 0.67945 -0.305054)
			(stroke
				(width 0.1)
				(type default)
			)
			(layer "B.Fab")
		)
		(pad "1" smd circle
			(at 0.40005 0 180)
			(size 0 0)
			(layers "B.Cu" "B.Mask" "B.Paste")
			(net "P3V3_AUX")
		)
		(pad "2" smd circle
			(at -0.40005 0 180)
			(size 0 0)
			(layers "B.Cu" "B.Mask" "B.Paste")
			(net "OCP_V3_2_P3V3_PWRGD")
		)
	)
	(footprint ""
		(layer "B.Cu")
		(at 416.02914 -161.064194)
		(property "Reference" "PC638"
			(at 0 0 0)
			(layer "B.SilkS")
			(hide yes)
			(effects
				(font
					(size 1.27 1.27)
				)
				(justify mirror)
			)
		)
		(property "Value" ""
			(at 0 0 0)
			(layer "B.Fab")
			(effects
				(font
					(size 1.27 1.27)
				)
				(justify mirror)
			)
		)
		(duplicate_pad_numbers_are_jumpers no)
		(fp_line
			(start -1.524 -0.762)
			(end -1.524 0.762)
			(stroke
				(width 0.1524)
				(type default)
			)
			(layer "B.SilkS")
		)
		(fp_line
			(start -1.524 0.762)
			(end 1.524 0.762)
			(stroke
				(width 0.1524)
				(type default)
			)
			(layer "B.SilkS")
		)
		(fp_line
			(start 1.524 -0.762)
			(end -1.524 -0.762)
			(stroke
				(width 0.1524)
				(type default)
			)
			(layer "B.SilkS")
		)
		(fp_line
			(start 1.524 0.762)
			(end 1.524 -0.762)
			(stroke
				(width 0.1524)
				(type default)
			)
			(layer "B.SilkS")
		)
		(fp_line
			(start -1.1049 -0.724916)
			(end 1.1049 -0.724916)
			(stroke
				(width 0.1)
				(type default)
			)
			(layer "B.Fab")
		)
		(fp_line
			(start -1.1049 0.724916)
			(end -1.1049 -0.724916)
			(stroke
				(width 0.1)
				(type default)
			)
			(layer "B.Fab")
		)
		(fp_line
			(start 1.1049 -0.724916)
			(end 1.1049 0.724916)
			(stroke
				(width 0.1)
				(type default)
			)
			(layer "B.Fab")
		)
		(fp_line
			(start 1.1049 0.724916)
			(end -1.1049 0.724916)
			(stroke
				(width 0.1)
				(type default)
			)
			(layer "B.Fab")
		)
		(pad "1" smd rect
			(at 0.889 0)
			(size 1.016 1.27)
			(layers "B.Cu" "B.Mask" "B.Paste")
			(net "SW_P12V_PVCCINFAON_CPU0_FLT")
		)
		(pad "2" smd rect
			(at -0.889 0)
			(size 1.016 1.27)
			(layers "B.Cu" "B.Mask" "B.Paste")
			(net "GND")
		)
	)
)
